(kicad_pcb
	(version 20260206)
	(generator "pcbnew")
	(generator_version "10.0")
	(general
		(thickness 1.6)
		(legacy_teardrops no)
	)
	(paper "A4")
	(title_block
		(title "01162023_DA0F0TEBIF0_F0T_Expander_BD_F_brd_V02_OCP.brd")
		(comment 1 "Grand Teton / footprints 1691-1697 of 9728")
	)
	(layers
		(0 "F.Cu" signal "TOP")
		(4 "In1.Cu" signal "GND")
		(6 "In2.Cu" signal "VCC")
		(8 "In3.Cu" signal "VCC1")
		(10 "In4.Cu" signal "GND1")
		(12 "In5.Cu" signal "IN1")
		(14 "In6.Cu" signal "GND2")
		(16 "In7.Cu" signal "IN2")
		(18 "In8.Cu" signal "GND3")
		(20 "In9.Cu" signal "IN3")
		(22 "In10.Cu" signal "GND4")
		(24 "In11.Cu" signal "IN4")
		(26 "In12.Cu" signal "GND5")
		(28 "In13.Cu" signal "IN5")
		(30 "In14.Cu" signal "GND6")
		(32 "In15.Cu" signal "IN6")
		(34 "In16.Cu" signal "GND7")
		(2 "B.Cu" signal "BOTTOM")
		(9 "F.Adhes" user "F.Adhesive")
		(11 "B.Adhes" user "B.Adhesive")
		(13 "F.Paste" user "Package Geometry/Pastemask Top")
		(15 "B.Paste" user "Package Geometry/Pastemask Bottom")
		(5 "F.SilkS" user "Ref Des/Silkscreen Top")
		(7 "B.SilkS" user "Ref Des/Silkscreen Bottom")
		(1 "F.Mask" user "Board Geometry/Soldermask Top")
		(3 "B.Mask" user "Board Geometry/Soldermask Bottom")
		(17 "Dwgs.User" user "User.Drawings")
		(19 "Cmts.User" user "User.Comments")
		(21 "Eco1.User" user "User.Eco1")
		(23 "Eco2.User" user "User.Eco2")
		(25 "Edge.Cuts" user "Board Geometry/Outline")
		(27 "Margin" user)
		(31 "F.CrtYd" user "Package Geometry/Place Bound Top")
		(29 "B.CrtYd" user "Package Geometry/Place Bound Bottom")
		(35 "F.Fab" user "Ref Des/Assembly Top")
		(33 "B.Fab" user "Ref Des/Assembly Bottom")
	)
	(footprint ""
		(layer "F.Cu")
		(at 376.312684 -87.6808)
		(property "Reference" "R1744"
			(at 0 0 0)
			(layer "F.SilkS")
			(hide yes)
			(effects
				(font
					(size 1.27 1.27)
				)
			)
		)
		(property "Value" ""
			(at 0 0 0)
			(layer "F.Fab")
			(effects
				(font
					(size 1.27 1.27)
				)
			)
		)
		(duplicate_pad_numbers_are_jumpers no)
		(fp_line
			(start -0.7874 -0.4064)
			(end 0.7874 -0.4064)
			(stroke
				(width 0.1524)
				(type default)
			)
			(layer "F.SilkS")
		)
		(fp_line
			(start -0.7874 0.4064)
			(end -0.7874 -0.4064)
			(stroke
				(width 0.1524)
				(type default)
			)
			(layer "F.SilkS")
		)
		(fp_line
			(start 0.7874 -0.4064)
			(end 0.7874 0.4064)
			(stroke
				(width 0.1524)
				(type default)
			)
			(layer "F.SilkS")
		)
		(fp_line
			(start 0.7874 0.4064)
			(end -0.7874 0.4064)
			(stroke
				(width 0.1524)
				(type default)
			)
			(layer "F.SilkS")
		)
		(fp_line
			(start -0.67945 -0.305054)
			(end -0.12065 -0.305054)
			(stroke
				(width 0.1)
				(type default)
			)
			(layer "F.Fab")
		)
		(fp_line
			(start -0.67945 0.3048)
			(end -0.67945 -0.305054)
			(stroke
				(width 0.1)
				(type default)
			)
			(layer "F.Fab")
		)
		(fp_line
			(start -0.12065 -0.305054)
			(end -0.12065 -0.2794)
			(stroke
				(width 0.1)
				(type default)
			)
			(layer "F.Fab")
		)
		(fp_line
			(start -0.12065 -0.2794)
			(end 0.12065 -0.2794)
			(stroke
				(width 0.1)
				(type default)
			)
			(layer "F.Fab")
		)
		(fp_line
			(start -0.12065 0.2794)
			(end -0.12065 0.3048)
			(stroke
				(width 0.1)
				(type default)
			)
			(layer "F.Fab")
		)
		(fp_line
			(start -0.12065 0.3048)
			(end -0.67945 0.3048)
			(stroke
				(width 0.1)
				(type default)
			)
			(layer "F.Fab")
		)
		(fp_line
			(start 0.120396 0.2794)
			(end -0.12065 0.2794)
			(stroke
				(width 0.1)
				(type default)
			)
			(layer "F.Fab")
		)
		(fp_line
			(start 0.120396 0.3048)
			(end 0.120396 0.2794)
			(stroke
				(width 0.1)
				(type default)
			)
			(layer "F.Fab")
		)
		(fp_line
			(start 0.12065 -0.3048)
			(end 0.67945 -0.3048)
			(stroke
				(width 0.1)
				(type default)
			)
			(layer "F.Fab")
		)
		(fp_line
			(start 0.12065 -0.2794)
			(end 0.12065 -0.3048)
			(stroke
				(width 0.1)
				(type default)
			)
			(layer "F.Fab")
		)
		(fp_line
			(start 0.67945 -0.3048)
			(end 0.67945 0.3048)
			(stroke
				(width 0.1)
				(type default)
			)
			(layer "F.Fab")
		)
		(fp_line
			(start 0.67945 0.3048)
			(end 0.120396 0.3048)
			(stroke
				(width 0.1)
				(type default)
			)
			(layer "F.Fab")
		)
		(pad "1" smd circle
			(at -0.40005 0)
			(size 0 0)
			(layers "F.Cu" "F.Mask" "F.Paste")
			(net "P3V3_AUX")
		)
		(pad "2" smd circle
			(at 0.40005 0)
			(size 0 0)
			(layers "F.Cu" "F.Mask" "F.Paste")
			(net "SMB_BIC_I2C6_MUX_NIC_ADC_R_SCL")
		)
	)
	(footprint ""
		(layer "F.Cu")
		(at 221.647512 -231.416606 -90)
		(property "Reference" "R4548"
			(at 0 0 270)
			(layer "F.SilkS")
			(hide yes)
			(effects
				(font
					(size 1.27 1.27)
				)
			)
		)
		(property "Value" ""
			(at 0 0 270)
			(layer "F.Fab")
			(effects
				(font
					(size 1.27 1.27)
				)
			)
		)
		(duplicate_pad_numbers_are_jumpers no)
		(fp_line
			(start -0.7874 0.4064)
			(end -0.7874 -0.4064)
			(stroke
				(width 0.1524)
				(type default)
			)
			(layer "F.SilkS")
		)
		(fp_line
			(start 0.7874 0.4064)
			(end -0.7874 0.4064)
			(stroke
				(width 0.1524)
				(type default)
			)
			(layer "F.SilkS")
		)
		(fp_line
			(start -0.7874 -0.4064)
			(end 0.7874 -0.4064)
			(stroke
				(width 0.1524)
				(type default)
			)
			(layer "F.SilkS")
		)
		(fp_line
			(start 0.7874 -0.4064)
			(end 0.7874 0.4064)
			(stroke
				(width 0.1524)
				(type default)
			)
			(layer "F.SilkS")
		)
		(fp_line
			(start -0.67945 0.3048)
			(end -0.67945 -0.305054)
			(stroke
				(width 0.1)
				(type default)
			)
			(layer "F.Fab")
		)
		(fp_line
			(start -0.12065 0.3048)
			(end -0.67945 0.3048)
			(stroke
				(width 0.1)
				(type default)
			)
			(layer "F.Fab")
		)
		(fp_line
			(start 0.120396 0.3048)
			(end 0.120396 0.2794)
			(stroke
				(width 0.1)
				(type default)
			)
			(layer "F.Fab")
		)
		(fp_line
			(start 0.67945 0.3048)
			(end 0.120396 0.3048)
			(stroke
				(width 0.1)
				(type default)
			)
			(layer "F.Fab")
		)
		(fp_line
			(start -0.12065 0.2794)
			(end -0.12065 0.3048)
			(stroke
				(width 0.1)
				(type default)
			)
			(layer "F.Fab")
		)
		(fp_line
			(start 0.120396 0.2794)
			(end -0.12065 0.2794)
			(stroke
				(width 0.1)
				(type default)
			)
			(layer "F.Fab")
		)
		(fp_line
			(start -0.12065 -0.2794)
			(end 0.12065 -0.2794)
			(stroke
				(width 0.1)
				(type default)
			)
			(layer "F.Fab")
		)
		(fp_line
			(start 0.12065 -0.2794)
			(end 0.12065 -0.3048)
			(stroke
				(width 0.1)
				(type default)
			)
			(layer "F.Fab")
		)
		(fp_line
			(start 0.12065 -0.3048)
			(end 0.67945 -0.3048)
			(stroke
				(width 0.1)
				(type default)
			)
			(layer "F.Fab")
		)
		(fp_line
			(start 0.67945 -0.3048)
			(end 0.67945 0.3048)
			(stroke
				(width 0.1)
				(type default)
			)
			(layer "F.Fab")
		)
		(fp_line
			(start -0.67945 -0.305054)
			(end -0.12065 -0.305054)
			(stroke
				(width 0.1)
				(type default)
			)
			(layer "F.Fab")
		)
		(fp_line
			(start -0.12065 -0.305054)
			(end -0.12065 -0.2794)
			(stroke
				(width 0.1)
				(type default)
			)
			(layer "F.Fab")
		)
		(pad "1" smd circle
			(at -0.40005 0 270)
			(size 0 0)
			(layers "F.Cu" "F.Mask" "F.Paste")
			(net "GND")
		)
		(pad "2" smd circle
			(at 0.40005 0 270)
			(size 0 0)
			(layers "F.Cu" "F.Mask" "F.Paste")
			(net "REV_ID1")
		)
	)
	(footprint ""
		(layer "F.Cu")
		(at 288.573718 -27.006296 -90)
		(property "Reference" "PC954"
			(at 0 0 270)
			(layer "F.SilkS")
			(hide yes)
			(effects
				(font
					(size 1.27 1.27)
				)
			)
		)
		(property "Value" ""
			(at 0 0 270)
			(layer "F.Fab")
			(effects
				(font
					(size 1.27 1.27)
				)
			)
		)
		(duplicate_pad_numbers_are_jumpers no)
		(fp_line
			(start -0.7874 0.4064)
			(end -0.7874 -0.4064)
			(stroke
				(width 0.1524)
				(type default)
			)
			(layer "F.SilkS")
		)
		(fp_line
			(start 0.7874 0.4064)
			(end -0.7874 0.4064)
			(stroke
				(width 0.1524)
				(type default)
			)
			(layer "F.SilkS")
		)
		(fp_line
			(start -0.7874 -0.4064)
			(end 0.7874 -0.4064)
			(stroke
				(width 0.1524)
				(type default)
			)
			(layer "F.SilkS")
		)
		(fp_line
			(start 0.7874 -0.4064)
			(end 0.7874 0.4064)
			(stroke
				(width 0.1524)
				(type default)
			)
			(layer "F.SilkS")
		)
		(fp_line
			(start -0.67945 0.3048)
			(end -0.67945 -0.305054)
			(stroke
				(width 0.1)
				(type default)
			)
			(layer "F.Fab")
		)
		(fp_line
			(start -0.12065 0.3048)
			(end -0.67945 0.3048)
			(stroke
				(width 0.1)
				(type default)
			)
			(layer "F.Fab")
		)
		(fp_line
			(start 0.120396 0.3048)
			(end 0.120396 0.2794)
			(stroke
				(width 0.1)
				(type default)
			)
			(layer "F.Fab")
		)
		(fp_line
			(start 0.67945 0.3048)
			(end 0.120396 0.3048)
			(stroke
				(width 0.1)
				(type default)
			)
			(layer "F.Fab")
		)
		(fp_line
			(start -0.12065 0.2794)
			(end -0.12065 0.3048)
			(stroke
				(width 0.1)
				(type default)
			)
			(layer "F.Fab")
		)
		(fp_line
			(start 0.120396 0.2794)
			(end -0.12065 0.2794)
			(stroke
				(width 0.1)
				(type default)
			)
			(layer "F.Fab")
		)
		(fp_line
			(start -0.12065 -0.2794)
			(end 0.12065 -0.2794)
			(stroke
				(width 0.1)
				(type default)
			)
			(layer "F.Fab")
		)
		(fp_line
			(start 0.12065 -0.2794)
			(end 0.12065 -0.3048)
			(stroke
				(width 0.1)
				(type default)
			)
			(layer "F.Fab")
		)
		(fp_line
			(start 0.12065 -0.3048)
			(end 0.67945 -0.3048)
			(stroke
				(width 0.1)
				(type default)
			)
			(layer "F.Fab")
		)
		(fp_line
			(start 0.67945 -0.3048)
			(end 0.67945 0.3048)
			(stroke
				(width 0.1)
				(type default)
			)
			(layer "F.Fab")
		)
		(fp_line
			(start -0.67945 -0.305054)
			(end -0.12065 -0.305054)
			(stroke
				(width 0.1)
				(type default)
			)
			(layer "F.Fab")
		)
		(fp_line
			(start -0.12065 -0.305054)
			(end -0.12065 -0.2794)
			(stroke
				(width 0.1)
				(type default)
			)
			(layer "F.Fab")
		)
		(pad "1" smd circle
			(at -0.40005 0 270)
			(size 0 0)
			(layers "F.Cu" "F.Mask" "F.Paste")
			(net "P3V3_SSD10_CO_MODE")
		)
		(pad "2" smd circle
			(at 0.40005 0 270)
			(size 0 0)
			(layers "F.Cu" "F.Mask" "F.Paste")
			(net "GND")
		)
	)
	(footprint ""
		(layer "F.Cu")
		(at 400.543776 -45.88891)
		(property "Reference" "R652"
			(at 0 0 0)
			(layer "F.SilkS")
			(hide yes)
			(effects
				(font
					(size 1.27 1.27)
				)
			)
		)
		(property "Value" ""
			(at 0 0 0)
			(layer "F.Fab")
			(effects
				(font
					(size 1.27 1.27)
				)
			)
		)
		(duplicate_pad_numbers_are_jumpers no)
		(fp_line
			(start -0.7874 -0.4064)
			(end 0.7874 -0.4064)
			(stroke
				(width 0.1524)
				(type default)
			)
			(layer "F.SilkS")
		)
		(fp_line
			(start -0.7874 0.4064)
			(end -0.7874 -0.4064)
			(stroke
				(width 0.1524)
				(type default)
			)
			(layer "F.SilkS")
		)
		(fp_line
			(start 0.7874 -0.4064)
			(end 0.7874 0.4064)
			(stroke
				(width 0.1524)
				(type default)
			)
			(layer "F.SilkS")
		)
		(fp_line
			(start 0.7874 0.4064)
			(end -0.7874 0.4064)
			(stroke
				(width 0.1524)
				(type default)
			)
			(layer "F.SilkS")
		)
		(fp_line
			(start -0.67945 -0.305054)
			(end -0.12065 -0.305054)
			(stroke
				(width 0.1)
				(type default)
			)
			(layer "F.Fab")
		)
		(fp_line
			(start -0.67945 0.3048)
			(end -0.67945 -0.305054)
			(stroke
				(width 0.1)
				(type default)
			)
			(layer "F.Fab")
		)
		(fp_line
			(start -0.12065 -0.305054)
			(end -0.12065 -0.2794)
			(stroke
				(width 0.1)
				(type default)
			)
			(layer "F.Fab")
		)
		(fp_line
			(start -0.12065 -0.2794)
			(end 0.12065 -0.2794)
			(stroke
				(width 0.1)
				(type default)
			)
			(layer "F.Fab")
		)
		(fp_line
			(start -0.12065 0.2794)
			(end -0.12065 0.3048)
			(stroke
				(width 0.1)
				(type default)
			)
			(layer "F.Fab")
		)
		(fp_line
			(start -0.12065 0.3048)
			(end -0.67945 0.3048)
			(stroke
				(width 0.1)
				(type default)
			)
			(layer "F.Fab")
		)
		(fp_line
			(start 0.120396 0.2794)
			(end -0.12065 0.2794)
			(stroke
				(width 0.1)
				(type default)
			)
			(layer "F.Fab")
		)
		(fp_line
			(start 0.120396 0.3048)
			(end 0.120396 0.2794)
			(stroke
				(width 0.1)
				(type default)
			)
			(layer "F.Fab")
		)
		(fp_line
			(start 0.12065 -0.3048)
			(end 0.67945 -0.3048)
			(stroke
				(width 0.1)
				(type default)
			)
			(layer "F.Fab")
		)
		(fp_line
			(start 0.12065 -0.2794)
			(end 0.12065 -0.3048)
			(stroke
				(width 0.1)
				(type default)
			)
			(layer "F.Fab")
		)
		(fp_line
			(start 0.67945 -0.3048)
			(end 0.67945 0.3048)
			(stroke
				(width 0.1)
				(type default)
			)
			(layer "F.Fab")
		)
		(fp_line
			(start 0.67945 0.3048)
			(end 0.120396 0.3048)
			(stroke
				(width 0.1)
				(type default)
			)
			(layer "F.Fab")
		)
		(pad "1" smd circle
			(at -0.40005 0)
			(size 0 0)
			(layers "F.Cu" "F.Mask" "F.Paste")
			(net "SSD13_ADC_A0")
		)
		(pad "2" smd circle
			(at 0.40005 0)
			(size 0 0)
			(layers "F.Cu" "F.Mask" "F.Paste")
			(net "GND")
		)
	)
	(footprint ""
		(layer "F.Cu")
		(at 93.003878 -291.722048 90)
		(property "Reference" "C2754"
			(at 0 0 90)
			(layer "F.SilkS")
			(hide yes)
			(effects
				(font
					(size 1.27 1.27)
				)
			)
		)
		(property "Value" ""
			(at 0 0 90)
			(layer "F.Fab")
			(effects
				(font
					(size 1.27 1.27)
				)
			)
		)
		(duplicate_pad_numbers_are_jumpers no)
		(fp_line
			(start 0.7874 -0.4064)
			(end 0.7874 0.4064)
			(stroke
				(width 0.1524)
				(type default)
			)
			(layer "F.SilkS")
		)
		(fp_line
			(start -0.7874 -0.4064)
			(end 0.7874 -0.4064)
			(stroke
				(width 0.1524)
				(type default)
			)
			(layer "F.SilkS")
		)
		(fp_line
			(start 0.7874 0.4064)
			(end -0.7874 0.4064)
			(stroke
				(width 0.1524)
				(type default)
			)
			(layer "F.SilkS")
		)
		(fp_line
			(start -0.7874 0.4064)
			(end -0.7874 -0.4064)
			(stroke
				(width 0.1524)
				(type default)
			)
			(layer "F.SilkS")
		)
		(fp_line
			(start -0.12065 -0.305054)
			(end -0.12065 -0.2794)
			(stroke
				(width 0.1)
				(type default)
			)
			(layer "F.Fab")
		)
		(fp_line
			(start -0.67945 -0.305054)
			(end -0.12065 -0.305054)
			(stroke
				(width 0.1)
				(type default)
			)
			(layer "F.Fab")
		)
		(fp_line
			(start 0.67945 -0.3048)
			(end 0.67945 0.3048)
			(stroke
				(width 0.1)
				(type default)
			)
			(layer "F.Fab")
		)
		(fp_line
			(start 0.12065 -0.3048)
			(end 0.67945 -0.3048)
			(stroke
				(width 0.1)
				(type default)
			)
			(layer "F.Fab")
		)
		(fp_line
			(start 0.12065 -0.2794)
			(end 0.12065 -0.3048)
			(stroke
				(width 0.1)
				(type default)
			)
			(layer "F.Fab")
		)
		(fp_line
			(start -0.12065 -0.2794)
			(end 0.12065 -0.2794)
			(stroke
				(width 0.1)
				(type default)
			)
			(layer "F.Fab")
		)
		(fp_line
			(start 0.120396 0.2794)
			(end -0.12065 0.2794)
			(stroke
				(width 0.1)
				(type default)
			)
			(layer "F.Fab")
		)
		(fp_line
			(start -0.12065 0.2794)
			(end -0.12065 0.3048)
			(stroke
				(width 0.1)
				(type default)
			)
			(layer "F.Fab")
		)
		(fp_line
			(start 0.67945 0.3048)
			(end 0.120396 0.3048)
			(stroke
				(width 0.1)
				(type default)
			)
			(layer "F.Fab")
		)
		(fp_line
			(start 0.120396 0.3048)
			(end 0.120396 0.2794)
			(stroke
				(width 0.1)
				(type default)
			)
			(layer "F.Fab")
		)
		(fp_line
			(start -0.12065 0.3048)
			(end -0.67945 0.3048)
			(stroke
				(width 0.1)
				(type default)
			)
			(layer "F.Fab")
		)
		(fp_line
			(start -0.67945 0.3048)
			(end -0.67945 -0.305054)
			(stroke
				(width 0.1)
				(type default)
			)
			(layer "F.Fab")
		)
		(pad "1" smd circle
			(at -0.40005 0 90)
			(size 0 0)
			(layers "F.Cu" "F.Mask" "F.Paste")
			(net "GND")
		)
		(pad "2" smd circle
			(at 0.40005 0 90)
			(size 0 0)
			(layers "F.Cu" "F.Mask" "F.Paste")
			(net "P3V3_AUX")
		)
	)
	(footprint ""
		(layer "F.Cu")
		(at 168.378632 -356.244906 90)
		(property "Reference" "C394"
			(at 0 0 90)
			(layer "F.SilkS")
			(hide yes)
			(effects
				(font
					(size 1.27 1.27)
				)
			)
		)
		(property "Value" ""
			(at 0 0 90)
			(layer "F.Fab")
			(effects
				(font
					(size 1.27 1.27)
				)
			)
		)
		(duplicate_pad_numbers_are_jumpers no)
		(fp_line
			(start 0.299974 -0.150114)
			(end 0.299974 0.150114)
			(stroke
				(width 0.1)
				(type default)
			)
			(layer "F.Fab")
		)
		(fp_line
			(start -0.299974 -0.150114)
			(end 0.299974 -0.150114)
			(stroke
				(width 0.1)
				(type default)
			)
			(layer "F.Fab")
		)
		(fp_line
			(start 0.299974 0.150114)
			(end -0.299974 0.150114)
			(stroke
				(width 0.1)
				(type default)
			)
			(layer "F.Fab")
		)
		(fp_line
			(start -0.299974 0.150114)
			(end -0.299974 -0.150114)
			(stroke
				(width 0.1)
				(type default)
			)
			(layer "F.Fab")
		)
		(pad "1" smd rect
			(at -0.2667 0 90)
			(size 0.3048 0.381)
			(layers "F.Cu" "F.Mask" "F.Paste")
			(net "P5E_PEX1_STN7_TX_DP<116>")
		)
		(pad "2" smd rect
			(at 0.2667 0 90)
			(size 0.3048 0.381)
			(layers "F.Cu" "F.Mask" "F.Paste")
			(net "P5E_PEX1_STN7_TX_C_DP<116>")
		)
	)
	(footprint ""
		(layer "F.Cu")
		(at 31.29407 -34.248852)
		(property "Reference" "R5648"
			(at 0 0 0)
			(layer "F.SilkS")
			(hide yes)
			(effects
				(font
					(size 1.27 1.27)
				)
			)
		)
		(property "Value" ""
			(at 0 0 0)
			(layer "F.Fab")
			(effects
				(font
					(size 1.27 1.27)
				)
			)
		)
		(duplicate_pad_numbers_are_jumpers no)
		(fp_line
			(start -0.7874 -0.4064)
			(end 0.7874 -0.4064)
			(stroke
				(width 0.1524)
				(type default)
			)
			(layer "F.SilkS")
		)
		(fp_line
			(start -0.7874 0.4064)
			(end -0.7874 -0.4064)
			(stroke
				(width 0.1524)
				(type default)
			)
			(layer "F.SilkS")
		)
		(fp_line
			(start 0.7874 -0.4064)
			(end 0.7874 0.4064)
			(stroke
				(width 0.1524)
				(type default)
			)
			(layer "F.SilkS")
		)
		(fp_line
			(start 0.7874 0.4064)
			(end -0.7874 0.4064)
			(stroke
				(width 0.1524)
				(type default)
			)
			(layer "F.SilkS")
		)
		(fp_line
			(start -0.67945 -0.305054)
			(end -0.12065 -0.305054)
			(stroke
				(width 0.1)
				(type default)
			)
			(layer "F.Fab")
		)
		(fp_line
			(start -0.67945 0.3048)
			(end -0.67945 -0.305054)
			(stroke
				(width 0.1)
				(type default)
			)
			(layer "F.Fab")
		)
		(fp_line
			(start -0.12065 -0.305054)
			(end -0.12065 -0.2794)
			(stroke
				(width 0.1)
				(type default)
			)
			(layer "F.Fab")
		)
		(fp_line
			(start -0.12065 -0.2794)
			(end 0.12065 -0.2794)
			(stroke
				(width 0.1)
				(type default)
			)
			(layer "F.Fab")
		)
		(fp_line
			(start -0.12065 0.2794)
			(end -0.12065 0.3048)
			(stroke
				(width 0.1)
				(type default)
			)
			(layer "F.Fab")
		)
		(fp_line
			(start -0.12065 0.3048)
			(end -0.67945 0.3048)
			(stroke
				(width 0.1)
				(type default)
			)
			(layer "F.Fab")
		)
		(fp_line
			(start 0.120396 0.2794)
			(end -0.12065 0.2794)
			(stroke
				(width 0.1)
				(type default)
			)
			(layer "F.Fab")
		)
		(fp_line
			(start 0.120396 0.3048)
			(end 0.120396 0.2794)
			(stroke
				(width 0.1)
				(type default)
			)
			(layer "F.Fab")
		)
		(fp_line
			(start 0.12065 -0.3048)
			(end 0.67945 -0.3048)
			(stroke
				(width 0.1)
				(type default)
			)
			(layer "F.Fab")
		)
		(fp_line
			(start 0.12065 -0.2794)
			(end 0.12065 -0.3048)
			(stroke
				(width 0.1)
				(type default)
			)
			(layer "F.Fab")
		)
		(fp_line
			(start 0.67945 -0.3048)
			(end 0.67945 0.3048)
			(stroke
				(width 0.1)
				(type default)
			)
			(layer "F.Fab")
		)
		(fp_line
			(start 0.67945 0.3048)
			(end 0.120396 0.3048)
			(stroke
				(width 0.1)
				(type default)
			)
			(layer "F.Fab")
		)
		(pad "1" smd circle
			(at -0.40005 0)
			(size 0 0)
			(layers "F.Cu" "F.Mask" "F.Paste")
			(net "RST_SMB_SSD1_ISO_N")
		)
		(pad "2" smd circle
			(at 0.40005 0)
			(size 0 0)
			(layers "F.Cu" "F.Mask" "F.Paste")
			(net "P3V3_SSD1")
		)
	)
)
